(kicad_pcb
	(version 20260206)
	(generator "pcbnew")
	(generator_version "10.0")
	(general
		(thickness 1.6)
		(legacy_teardrops no)
	)
	(paper "A4")
	(title_block
		(title "12092022_DA0F0TMDCD0_F0T_Management_Board_D_brd_V3_OCP.brd")
		(comment 1 "Grand Teton / footprints 1251-1256 of 1440")
	)
	(layers
		(0 "F.Cu" signal "TOP")
		(4 "In1.Cu" signal "GND")
		(6 "In2.Cu" signal "IN1")
		(8 "In3.Cu" signal "GND1")
		(10 "In4.Cu" signal "IN2")
		(12 "In5.Cu" signal "VCC")
		(14 "In6.Cu" signal "VCC1")
		(16 "In7.Cu" signal "IN3")
		(18 "In8.Cu" signal "GND2")
		(20 "In9.Cu" signal "IN4")
		(22 "In10.Cu" signal "GND3")
		(2 "B.Cu" signal "BOTTOM")
		(9 "F.Adhes" user "F.Adhesive")
		(11 "B.Adhes" user "B.Adhesive")
		(13 "F.Paste" user "Package Geometry/Pastemask Top")
		(15 "B.Paste" user "Package Geometry/Pastemask Bottom")
		(5 "F.SilkS" user "Ref Des/Silkscreen Top")
		(7 "B.SilkS" user "Ref Des/Silkscreen Bottom")
		(1 "F.Mask" user "Board Geometry/Soldermask Top")
		(3 "B.Mask" user "Board Geometry/Soldermask Bottom")
		(17 "Dwgs.User" user "User.Drawings")
		(19 "Cmts.User" user "User.Comments")
		(21 "Eco1.User" user "User.Eco1")
		(23 "Eco2.User" user "User.Eco2")
		(25 "Edge.Cuts" user "Board Geometry/Outline")
		(27 "Margin" user)
		(31 "F.CrtYd" user "Package Geometry/Place Bound Top")
		(29 "B.CrtYd" user "Package Geometry/Place Bound Bottom")
		(35 "F.Fab" user "Ref Des/Assembly Top")
		(33 "B.Fab" user "Ref Des/Assembly Bottom")
	)
	(footprint ""
		(layer "B.Cu")
		(at 66.4972 -62.0268 -90)
		(property "Reference" "R129"
			(at 0 0 90)
			(layer "B.SilkS")
			(hide yes)
			(effects
				(font
					(size 1.27 1.27)
				)
				(justify mirror)
			)
		)
		(property "Value" ""
			(at 0 0 90)
			(layer "B.Fab")
			(effects
				(font
					(size 1.27 1.27)
				)
				(justify mirror)
			)
		)
		(duplicate_pad_numbers_are_jumpers no)
		(fp_line
			(start -0.7874 0.4064)
			(end 0.7874 0.4064)
			(stroke
				(width 0.1524)
				(type default)
			)
			(layer "B.SilkS")
		)
		(fp_line
			(start 0.7874 0.4064)
			(end 0.7874 -0.4064)
			(stroke
				(width 0.1524)
				(type default)
			)
			(layer "B.SilkS")
		)
		(fp_line
			(start -0.7874 -0.4064)
			(end -0.7874 0.4064)
			(stroke
				(width 0.1524)
				(type default)
			)
			(layer "B.SilkS")
		)
		(fp_line
			(start 0.7874 -0.4064)
			(end -0.7874 -0.4064)
			(stroke
				(width 0.1524)
				(type default)
			)
			(layer "B.SilkS")
		)
		(fp_line
			(start -0.67945 0.3048)
			(end -0.120396 0.3048)
			(stroke
				(width 0.1)
				(type default)
			)
			(layer "B.Fab")
		)
		(fp_line
			(start -0.120396 0.3048)
			(end -0.120396 0.2794)
			(stroke
				(width 0.1)
				(type default)
			)
			(layer "B.Fab")
		)
		(fp_line
			(start 0.12065 0.3048)
			(end 0.67945 0.3048)
			(stroke
				(width 0.1)
				(type default)
			)
			(layer "B.Fab")
		)
		(fp_line
			(start 0.67945 0.3048)
			(end 0.67945 -0.305054)
			(stroke
				(width 0.1)
				(type default)
			)
			(layer "B.Fab")
		)
		(fp_line
			(start -0.120396 0.2794)
			(end 0.12065 0.2794)
			(stroke
				(width 0.1)
				(type default)
			)
			(layer "B.Fab")
		)
		(fp_line
			(start 0.12065 0.2794)
			(end 0.12065 0.3048)
			(stroke
				(width 0.1)
				(type default)
			)
			(layer "B.Fab")
		)
		(fp_line
			(start -0.12065 -0.2794)
			(end -0.12065 -0.3048)
			(stroke
				(width 0.1)
				(type default)
			)
			(layer "B.Fab")
		)
		(fp_line
			(start 0.12065 -0.2794)
			(end -0.12065 -0.2794)
			(stroke
				(width 0.1)
				(type default)
			)
			(layer "B.Fab")
		)
		(fp_line
			(start -0.67945 -0.3048)
			(end -0.67945 0.3048)
			(stroke
				(width 0.1)
				(type default)
			)
			(layer "B.Fab")
		)
		(fp_line
			(start -0.12065 -0.3048)
			(end -0.67945 -0.3048)
			(stroke
				(width 0.1)
				(type default)
			)
			(layer "B.Fab")
		)
		(fp_line
			(start 0.12065 -0.305054)
			(end 0.12065 -0.2794)
			(stroke
				(width 0.1)
				(type default)
			)
			(layer "B.Fab")
		)
		(fp_line
			(start 0.67945 -0.305054)
			(end 0.12065 -0.305054)
			(stroke
				(width 0.1)
				(type default)
			)
			(layer "B.Fab")
		)
		(pad "1" smd circle
			(at 0.40005 0 90)
			(size 0 0)
			(layers "B.Cu" "B.Mask" "B.Paste")
			(net "ESPI_LPC_D1_IO1")
		)
		(pad "2" smd circle
			(at -0.40005 0 90)
			(size 0 0)
			(layers "B.Cu" "B.Mask" "B.Paste")
			(net "ESPI_LPC_LAD1_IO1")
		)
	)
	(footprint ""
		(layer "B.Cu")
		(at 23.573486 -106.50982 -90)
		(property "Reference" "R40"
			(at 0 0 90)
			(layer "B.SilkS")
			(hide yes)
			(effects
				(font
					(size 1.27 1.27)
				)
				(justify mirror)
			)
		)
		(property "Value" ""
			(at 0 0 90)
			(layer "B.Fab")
			(effects
				(font
					(size 1.27 1.27)
				)
				(justify mirror)
			)
		)
		(duplicate_pad_numbers_are_jumpers no)
		(fp_line
			(start -0.7874 0.4064)
			(end 0.7874 0.4064)
			(stroke
				(width 0.1524)
				(type default)
			)
			(layer "B.SilkS")
		)
		(fp_line
			(start 0.7874 0.4064)
			(end 0.7874 -0.4064)
			(stroke
				(width 0.1524)
				(type default)
			)
			(layer "B.SilkS")
		)
		(fp_line
			(start -0.7874 -0.4064)
			(end -0.7874 0.4064)
			(stroke
				(width 0.1524)
				(type default)
			)
			(layer "B.SilkS")
		)
		(fp_line
			(start 0.7874 -0.4064)
			(end -0.7874 -0.4064)
			(stroke
				(width 0.1524)
				(type default)
			)
			(layer "B.SilkS")
		)
		(fp_line
			(start -0.67945 0.3048)
			(end -0.120396 0.3048)
			(stroke
				(width 0.1)
				(type default)
			)
			(layer "B.Fab")
		)
		(fp_line
			(start -0.120396 0.3048)
			(end -0.120396 0.2794)
			(stroke
				(width 0.1)
				(type default)
			)
			(layer "B.Fab")
		)
		(fp_line
			(start 0.12065 0.3048)
			(end 0.67945 0.3048)
			(stroke
				(width 0.1)
				(type default)
			)
			(layer "B.Fab")
		)
		(fp_line
			(start 0.67945 0.3048)
			(end 0.67945 -0.305054)
			(stroke
				(width 0.1)
				(type default)
			)
			(layer "B.Fab")
		)
		(fp_line
			(start -0.120396 0.2794)
			(end 0.12065 0.2794)
			(stroke
				(width 0.1)
				(type default)
			)
			(layer "B.Fab")
		)
		(fp_line
			(start 0.12065 0.2794)
			(end 0.12065 0.3048)
			(stroke
				(width 0.1)
				(type default)
			)
			(layer "B.Fab")
		)
		(fp_line
			(start -0.12065 -0.2794)
			(end -0.12065 -0.3048)
			(stroke
				(width 0.1)
				(type default)
			)
			(layer "B.Fab")
		)
		(fp_line
			(start 0.12065 -0.2794)
			(end -0.12065 -0.2794)
			(stroke
				(width 0.1)
				(type default)
			)
			(layer "B.Fab")
		)
		(fp_line
			(start -0.67945 -0.3048)
			(end -0.67945 0.3048)
			(stroke
				(width 0.1)
				(type default)
			)
			(layer "B.Fab")
		)
		(fp_line
			(start -0.12065 -0.3048)
			(end -0.67945 -0.3048)
			(stroke
				(width 0.1)
				(type default)
			)
			(layer "B.Fab")
		)
		(fp_line
			(start 0.12065 -0.305054)
			(end 0.12065 -0.2794)
			(stroke
				(width 0.1)
				(type default)
			)
			(layer "B.Fab")
		)
		(fp_line
			(start 0.67945 -0.305054)
			(end 0.12065 -0.305054)
			(stroke
				(width 0.1)
				(type default)
			)
			(layer "B.Fab")
		)
		(pad "1" smd circle
			(at 0.40005 0 90)
			(size 0 0)
			(layers "B.Cu" "B.Mask" "B.Paste")
			(net "GND")
		)
		(pad "2" smd circle
			(at -0.40005 0 90)
			(size 0 0)
			(layers "B.Cu" "B.Mask" "B.Paste")
			(net "PWRGD_SYS_PWROK")
		)
	)
	(footprint ""
		(layer "B.Cu")
		(at 59.055 -18.034)
		(property "Reference" "R730"
			(at 0 0 0)
			(layer "B.SilkS")
			(hide yes)
			(effects
				(font
					(size 1.27 1.27)
				)
				(justify mirror)
			)
		)
		(property "Value" ""
			(at 0 0 0)
			(layer "B.Fab")
			(effects
				(font
					(size 1.27 1.27)
				)
				(justify mirror)
			)
		)
		(duplicate_pad_numbers_are_jumpers no)
		(fp_line
			(start -0.7874 -0.4064)
			(end -0.7874 0.4064)
			(stroke
				(width 0.1524)
				(type default)
			)
			(layer "B.SilkS")
		)
		(fp_line
			(start -0.7874 0.4064)
			(end 0.7874 0.4064)
			(stroke
				(width 0.1524)
				(type default)
			)
			(layer "B.SilkS")
		)
		(fp_line
			(start 0.7874 -0.4064)
			(end -0.7874 -0.4064)
			(stroke
				(width 0.1524)
				(type default)
			)
			(layer "B.SilkS")
		)
		(fp_line
			(start 0.7874 0.4064)
			(end 0.7874 -0.4064)
			(stroke
				(width 0.1524)
				(type default)
			)
			(layer "B.SilkS")
		)
		(fp_line
			(start -0.67945 -0.3048)
			(end -0.67945 0.3048)
			(stroke
				(width 0.1)
				(type default)
			)
			(layer "B.Fab")
		)
		(fp_line
			(start -0.67945 0.3048)
			(end -0.120396 0.3048)
			(stroke
				(width 0.1)
				(type default)
			)
			(layer "B.Fab")
		)
		(fp_line
			(start -0.12065 -0.3048)
			(end -0.67945 -0.3048)
			(stroke
				(width 0.1)
				(type default)
			)
			(layer "B.Fab")
		)
		(fp_line
			(start -0.12065 -0.2794)
			(end -0.12065 -0.3048)
			(stroke
				(width 0.1)
				(type default)
			)
			(layer "B.Fab")
		)
		(fp_line
			(start -0.120396 0.2794)
			(end 0.12065 0.2794)
			(stroke
				(width 0.1)
				(type default)
			)
			(layer "B.Fab")
		)
		(fp_line
			(start -0.120396 0.3048)
			(end -0.120396 0.2794)
			(stroke
				(width 0.1)
				(type default)
			)
			(layer "B.Fab")
		)
		(fp_line
			(start 0.12065 -0.305054)
			(end 0.12065 -0.2794)
			(stroke
				(width 0.1)
				(type default)
			)
			(layer "B.Fab")
		)
		(fp_line
			(start 0.12065 -0.2794)
			(end -0.12065 -0.2794)
			(stroke
				(width 0.1)
				(type default)
			)
			(layer "B.Fab")
		)
		(fp_line
			(start 0.12065 0.2794)
			(end 0.12065 0.3048)
			(stroke
				(width 0.1)
				(type default)
			)
			(layer "B.Fab")
		)
		(fp_line
			(start 0.12065 0.3048)
			(end 0.67945 0.3048)
			(stroke
				(width 0.1)
				(type default)
			)
			(layer "B.Fab")
		)
		(fp_line
			(start 0.67945 -0.305054)
			(end 0.12065 -0.305054)
			(stroke
				(width 0.1)
				(type default)
			)
			(layer "B.Fab")
		)
		(fp_line
			(start 0.67945 0.3048)
			(end 0.67945 -0.305054)
			(stroke
				(width 0.1)
				(type default)
			)
			(layer "B.Fab")
		)
		(pad "1" smd circle
			(at 0.40005 0 180)
			(size 0 0)
			(layers "B.Cu" "B.Mask" "B.Paste")
			(net "P3V3_AUX")
		)
		(pad "2" smd circle
			(at -0.40005 0 180)
			(size 0 0)
			(layers "B.Cu" "B.Mask" "B.Paste")
			(net "FM_DEBUG_PORT_R_PRSNT_N")
		)
	)
	(footprint ""
		(layer "B.Cu")
		(at 54.917848 -49.255934 180)
		(property "Reference" "C84"
			(at 0 0 0)
			(layer "B.SilkS")
			(hide yes)
			(effects
				(font
					(size 1.27 1.27)
				)
				(justify mirror)
			)
		)
		(property "Value" ""
			(at 0 0 0)
			(layer "B.Fab")
			(effects
				(font
					(size 1.27 1.27)
				)
				(justify mirror)
			)
		)
		(duplicate_pad_numbers_are_jumpers no)
		(fp_line
			(start 0.7874 0.4064)
			(end 0.7874 -0.4064)
			(stroke
				(width 0.1524)
				(type default)
			)
			(layer "B.SilkS")
		)
		(fp_line
			(start 0.7874 -0.4064)
			(end -0.7874 -0.4064)
			(stroke
				(width 0.1524)
				(type default)
			)
			(layer "B.SilkS")
		)
		(fp_line
			(start -0.7874 0.4064)
			(end 0.7874 0.4064)
			(stroke
				(width 0.1524)
				(type default)
			)
			(layer "B.SilkS")
		)
		(fp_line
			(start -0.7874 -0.4064)
			(end -0.7874 0.4064)
			(stroke
				(width 0.1524)
				(type default)
			)
			(layer "B.SilkS")
		)
		(fp_line
			(start 0.67945 0.3048)
			(end 0.67945 -0.305054)
			(stroke
				(width 0.1)
				(type default)
			)
			(layer "B.Fab")
		)
		(fp_line
			(start 0.67945 -0.305054)
			(end 0.12065 -0.305054)
			(stroke
				(width 0.1)
				(type default)
			)
			(layer "B.Fab")
		)
		(fp_line
			(start 0.12065 0.3048)
			(end 0.67945 0.3048)
			(stroke
				(width 0.1)
				(type default)
			)
			(layer "B.Fab")
		)
		(fp_line
			(start 0.12065 0.2794)
			(end 0.12065 0.3048)
			(stroke
				(width 0.1)
				(type default)
			)
			(layer "B.Fab")
		)
		(fp_line
			(start 0.12065 -0.2794)
			(end -0.12065 -0.2794)
			(stroke
				(width 0.1)
				(type default)
			)
			(layer "B.Fab")
		)
		(fp_line
			(start 0.12065 -0.305054)
			(end 0.12065 -0.2794)
			(stroke
				(width 0.1)
				(type default)
			)
			(layer "B.Fab")
		)
		(fp_line
			(start -0.120396 0.3048)
			(end -0.120396 0.2794)
			(stroke
				(width 0.1)
				(type default)
			)
			(layer "B.Fab")
		)
		(fp_line
			(start -0.120396 0.2794)
			(end 0.12065 0.2794)
			(stroke
				(width 0.1)
				(type default)
			)
			(layer "B.Fab")
		)
		(fp_line
			(start -0.12065 -0.2794)
			(end -0.12065 -0.3048)
			(stroke
				(width 0.1)
				(type default)
			)
			(layer "B.Fab")
		)
		(fp_line
			(start -0.12065 -0.3048)
			(end -0.67945 -0.3048)
			(stroke
				(width 0.1)
				(type default)
			)
			(layer "B.Fab")
		)
		(fp_line
			(start -0.67945 0.3048)
			(end -0.120396 0.3048)
			(stroke
				(width 0.1)
				(type default)
			)
			(layer "B.Fab")
		)
		(fp_line
			(start -0.67945 -0.3048)
			(end -0.67945 0.3048)
			(stroke
				(width 0.1)
				(type default)
			)
			(layer "B.Fab")
		)
		(pad "1" smd circle
			(at 0.40005 0)
			(size 0 0)
			(layers "B.Cu" "B.Mask" "B.Paste")
			(net "P1V2_AUX")
		)
		(pad "2" smd circle
			(at -0.40005 0)
			(size 0 0)
			(layers "B.Cu" "B.Mask" "B.Paste")
			(net "GND")
		)
	)
	(footprint ""
		(layer "B.Cu")
		(at 68.608448 -26.594562 180)
		(property "Reference" "R421"
			(at 0 0 0)
			(layer "B.SilkS")
			(hide yes)
			(effects
				(font
					(size 1.27 1.27)
				)
				(justify mirror)
			)
		)
		(property "Value" ""
			(at 0 0 0)
			(layer "B.Fab")
			(effects
				(font
					(size 1.27 1.27)
				)
				(justify mirror)
			)
		)
		(duplicate_pad_numbers_are_jumpers no)
		(fp_line
			(start 0.7874 0.4064)
			(end 0.7874 -0.4064)
			(stroke
				(width 0.1524)
				(type default)
			)
			(layer "B.SilkS")
		)
		(fp_line
			(start 0.7874 -0.4064)
			(end -0.7874 -0.4064)
			(stroke
				(width 0.1524)
				(type default)
			)
			(layer "B.SilkS")
		)
		(fp_line
			(start -0.7874 0.4064)
			(end 0.7874 0.4064)
			(stroke
				(width 0.1524)
				(type default)
			)
			(layer "B.SilkS")
		)
		(fp_line
			(start -0.7874 -0.4064)
			(end -0.7874 0.4064)
			(stroke
				(width 0.1524)
				(type default)
			)
			(layer "B.SilkS")
		)
		(fp_line
			(start 0.67945 0.3048)
			(end 0.67945 -0.305054)
			(stroke
				(width 0.1)
				(type default)
			)
			(layer "B.Fab")
		)
		(fp_line
			(start 0.67945 -0.305054)
			(end 0.12065 -0.305054)
			(stroke
				(width 0.1)
				(type default)
			)
			(layer "B.Fab")
		)
		(fp_line
			(start 0.12065 0.3048)
			(end 0.67945 0.3048)
			(stroke
				(width 0.1)
				(type default)
			)
			(layer "B.Fab")
		)
		(fp_line
			(start 0.12065 0.2794)
			(end 0.12065 0.3048)
			(stroke
				(width 0.1)
				(type default)
			)
			(layer "B.Fab")
		)
		(fp_line
			(start 0.12065 -0.2794)
			(end -0.12065 -0.2794)
			(stroke
				(width 0.1)
				(type default)
			)
			(layer "B.Fab")
		)
		(fp_line
			(start 0.12065 -0.305054)
			(end 0.12065 -0.2794)
			(stroke
				(width 0.1)
				(type default)
			)
			(layer "B.Fab")
		)
		(fp_line
			(start -0.120396 0.3048)
			(end -0.120396 0.2794)
			(stroke
				(width 0.1)
				(type default)
			)
			(layer "B.Fab")
		)
		(fp_line
			(start -0.120396 0.2794)
			(end 0.12065 0.2794)
			(stroke
				(width 0.1)
				(type default)
			)
			(layer "B.Fab")
		)
		(fp_line
			(start -0.12065 -0.2794)
			(end -0.12065 -0.3048)
			(stroke
				(width 0.1)
				(type default)
			)
			(layer "B.Fab")
		)
		(fp_line
			(start -0.12065 -0.3048)
			(end -0.67945 -0.3048)
			(stroke
				(width 0.1)
				(type default)
			)
			(layer "B.Fab")
		)
		(fp_line
			(start -0.67945 0.3048)
			(end -0.120396 0.3048)
			(stroke
				(width 0.1)
				(type default)
			)
			(layer "B.Fab")
		)
		(fp_line
			(start -0.67945 -0.3048)
			(end -0.67945 0.3048)
			(stroke
				(width 0.1)
				(type default)
			)
			(layer "B.Fab")
		)
		(pad "1" smd circle
			(at 0.40005 0)
			(size 0 0)
			(layers "B.Cu" "B.Mask" "B.Paste")
			(net "SMB_BMC_MM16_R2_SDA")
		)
		(pad "2" smd circle
			(at -0.40005 0)
			(size 0 0)
			(layers "B.Cu" "B.Mask" "B.Paste")
			(net "SMB_BMC_MM16_SDA")
		)
	)
	(footprint ""
		(layer "B.Cu")
		(at 34.163 -67.437 -90)
		(property "Reference" "U20"
			(at -1.905 -1.87833 270)
			(unlocked yes)
			(layer "B.SilkS")
			(effects
				(font
					(size 0.7874 0.5842)
					(thickness 0.1524)
				)
				(justify mirror)
			)
		)
		(property "Value" ""
			(at 0 0 90)
			(layer "B.Fab")
			(effects
				(font
					(size 1.27 1.27)
				)
				(justify mirror)
			)
		)
		(duplicate_pad_numbers_are_jumpers no)
		(fp_line
			(start -1.7272 1.1176)
			(end 1.7272 1.1176)
			(stroke
				(width 0.1524)
				(type default)
			)
			(layer "B.SilkS")
		)
		(fp_line
			(start 1.7272 1.1176)
			(end 1.7272 -1.1176)
			(stroke
				(width 0.1524)
				(type default)
			)
			(layer "B.SilkS")
		)
		(fp_line
			(start 0 -0.7366)
			(end 0.254 -1.1176)
			(stroke
				(width 0.1524)
				(type default)
			)
			(layer "B.SilkS")
		)
		(fp_line
			(start -1.7272 -1.1176)
			(end -1.7272 1.1176)
			(stroke
				(width 0.1524)
				(type default)
			)
			(layer "B.SilkS")
		)
		(fp_line
			(start -1.7272 -1.1176)
			(end -0.254 -1.1176)
			(stroke
				(width 0.1524)
				(type default)
			)
			(layer "B.SilkS")
		)
		(fp_line
			(start -0.254 -1.1176)
			(end 0 -0.7366)
			(stroke
				(width 0.1524)
				(type default)
			)
			(layer "B.SilkS")
		)
		(fp_line
			(start 0.254 -1.1176)
			(end 1.7272 -1.1176)
			(stroke
				(width 0.1524)
				(type default)
			)
			(layer "B.SilkS")
		)
		(fp_poly
			(pts
				(xy 2.280412 -1.158748) (xy 3.08864 -1.427988) (xy 2.549906 -1.966976)
			)
			(stroke
				(width 0)
				(type default)
			)
			(fill yes)
			(layer "B.SilkS")
		)
		(fp_line
			(start -1.5748 1.1176)
			(end -1.5748 -1.1176)
			(stroke
				(width 0.1)
				(type default)
			)
			(layer "B.Fab")
		)
		(fp_line
			(start 1.5748 1.1176)
			(end -1.5748 1.1176)
			(stroke
				(width 0.1)
				(type default)
			)
			(layer "B.Fab")
		)
		(fp_line
			(start -1.5748 -1.1176)
			(end 1.5748 -1.1176)
			(stroke
				(width 0.1)
				(type default)
			)
			(layer "B.Fab")
		)
		(fp_line
			(start 1.5748 -1.1176)
			(end 1.5748 1.1176)
			(stroke
				(width 0.1)
				(type default)
			)
			(layer "B.Fab")
		)
		(fp_poly
			(pts
				(xy 1.9558 -0.649986) (xy 2.7178 -0.268986) (xy 2.7178 -1.030986)
			)
			(stroke
				(width 0)
				(type default)
			)
			(fill yes)
			(layer "B.Fab")
		)
		(pad "1" smd rect
			(at 0.999998 -0.649986 180)
			(size 0.3556 1.1176)
			(layers "B.Cu" "B.Mask" "B.Paste")
			(net "SPA_SIN_SW_DBG_R")
		)
		(pad "2" smd rect
			(at 0.999998 0 180)
			(size 0.3556 1.1176)
			(layers "B.Cu" "B.Mask" "B.Paste")
			(net "GND")
		)
		(pad "3" smd rect
			(at 0.999998 0.649986 180)
			(size 0.3556 1.1176)
			(layers "B.Cu" "B.Mask" "B.Paste")
			(net "UART_SYS_DBG_RX_R")
		)
		(pad "4" smd rect
			(at -0.999998 0.649986 180)
			(size 0.3556 1.1176)
			(layers "B.Cu" "B.Mask" "B.Paste")
			(net "SPA_SIN_SW_BUF_R")
		)
		(pad "5" smd rect
			(at -0.999998 0 180)
			(size 0.3556 1.1176)
			(layers "B.Cu" "B.Mask" "B.Paste")
			(net "P3V3_AUX")
		)
		(pad "6" smd rect
			(at -0.999998 -0.649986 180)
			(size 0.3556 1.1176)
			(layers "B.Cu" "B.Mask" "B.Paste")
			(net "FM_DBG_SW_N")
		)
	)
)
